# S9S_MB_2U (Grand Teton) — schematic netlist excerpt (pin names and nets, part order shuffled) for the footprints in the layout excerpt that follows; sources: Cadence DE-HDL packaged netlist, KiCad conversion of 03242023_DA0F0TMBIJ0_F0T_Motherboard_J_brd_V01_OCP.brd

J10  SCONN288_ADR50017P087CC  SCONN288_ADR50017-P087CC IO  pkg DDR288S_1-1VXB  page 91
  VIN_BULK0  = P12V_S3_AUX_CPU0_NVDIMM
  RFU0  = TP_CHE_CPU0_DIMM2_FRU_0
  VIN_MGMT  = P3V3_AUX
  HSCL  = I3C_SPD_DDREFGH_CPU0_LVC1_SCL_1
  HSDA  = I3C_SPD_DDREFGH_CPU0_LVC1_SDA
  VSS0  = GND
  DQ0_A  = M_E_CPU0_SA_DQ<0>
  VSS1  = GND
  DQ1_A  = M_E_CPU0_SA_DQ<1>
  VSS2  = GND
  DQS0_A_T  = M_E_CPU0_SA_DQS_DP<0>
  DQS0_A_C  = M_E_CPU0_SA_DQS_DN<0>
  VSS3  = GND
  DQ4_A  = M_E_CPU0_SA_DQ<4>
  VSS4  = GND
  DQ5_A  = M_E_CPU0_SA_DQ<5>
  VSS5  = GND
  DQ8_A  = M_E_CPU0_SA_DQ<8>
  VSS6  = GND
  DQ9_A  = M_E_CPU0_SA_DQ<9>
  VSS7  = GND
  DQS1_A_T  = M_E_CPU0_SA_DQS_DP<1>
  DQS1_A_C  = M_E_CPU0_SA_DQS_DN<1>
  VSS8  = GND
  DQ12_A  = M_E_CPU0_SA_DQ<12>
  VSS9  = GND
  DQ13_A  = M_E_CPU0_SA_DQ<13>
  VSS10  = GND
  DQ16_A  = M_E_CPU0_SA_DQ<16>
  VSS11  = GND
  DQ17_A  = M_E_CPU0_SA_DQ<17>
  VSS12  = GND
  DQS2_A_T  = M_E_CPU0_SA_DQS_DP<2>
  DQS2_A_C  = M_E_CPU0_SA_DQS_DN<2>
  VSS13  = GND
  DQ20_A  = M_E_CPU0_SA_DQ<20>
  VSS14  = GND
  DQ21_A  = M_E_CPU0_SA_DQ<21>
  VSS15  = GND
  DQ24_A  = M_E_CPU0_SA_DQ<24>
  VSS16  = GND
  DQ25_A  = M_E_CPU0_SA_DQ<25>
  VSS17  = GND
  DQS3_A_T  = M_E_CPU0_SA_DQS_DP<3>
  DQS3_A_C  = M_E_CPU0_SA_DQS_DN<3>
  VSS18  = GND
  DQ28_A  = M_E_CPU0_SA_DQ<28>
  VSS19  = GND
  DQ29_A  = M_E_CPU0_SA_DQ<29>
  VSS20  = GND
  CB0_A  = M_E_CPU0_SA_CB<0>
  VSS21  = GND
  CB1_A  = M_E_CPU0_SA_CB<1>
  VSS22  = GND
  DQS4_A_T  = M_E_CPU0_SA_DQS_DP<4>
  DQS4_A_C  = M_E_CPU0_SA_DQS_DN<4>
  VSS23  = GND
  CB4_A  = M_E_CPU0_SA_CB<4>
  VSS24  = GND
  CB5_A  = M_E_CPU0_SA_CB<5>
  VSS25  = GND
  ALERT_N  = M_E_CPU0_ALERT_N
  VSS26  = GND
  CS0_A_N  = M_E_CPU0_SA_CS_N<2>
  VSS27  = GND
  CA0_A  = M_E_CPU0_SA_CA<0>
  VSS28  = GND
  CA2_A  = M_E_CPU0_SA_CA<2>
  VSS29  = GND
  CA4_A  = M_E_CPU0_SA_CA<4>
  VSS30  = GND
  CA6_A  = M_E_CPU0_SA_CA<6>
  VSS31  = GND
  PAR_A  = M_E_CPU0_SA_PAR
  VSS32  = GND
  CA0_B  = M_E_CPU0_SB_CA<0>
  VSS33  = GND
  CA2_B  = M_E_CPU0_SB_CA<2>
  VSS34  = GND
  CA4_B  = M_E_CPU0_SB_CA<4>
  VSS35  = GND
  CA6_B  = M_E_CPU0_SB_CA<6>
  VSS36  = GND
  CS0_B_N  = M_E_CPU0_SB_CS_N<2>
  VSS37  = GND
  \lbd||rsp_a_n\  = M_E_CPU0_SA_RSP<1>
  \lbs||rsp_b_n\  = M_E_CPU0_SB_RSP<1>
  VSS38  = GND
  CB4_B  = M_E_CPU0_SB_CB<4>
  VSS39  = GND
  CB5_B  = M_E_CPU0_SB_CB<5>
  VSS40  = GND
  \dqs9_b_t||tdqs9_b_t||dbi4_b_n\  = M_E_CPU0_SB_DQS_DP<9>
  \dqs9_b_c||tdqs9_b_c\  = M_E_CPU0_SB_DQS_DN<9>
  VSS41  = GND
  CB0_B  = M_E_CPU0_SB_CB<0>
  VSS42  = GND
  CB1_B  = M_E_CPU0_SB_CB<1>
  VSS43  = GND
  DQ0_B  = M_E_CPU0_SB_DQ<0>
  VSS44  = GND
  DQ1_B  = M_E_CPU0_SB_DQ<1>
  VSS45  = GND
  DQS0_B_T  = M_E_CPU0_SB_DQS_DP<0>
  DQS0_B_C  = M_E_CPU0_SB_DQS_DN<0>
  VSS46  = GND
  DQ4_B  = M_E_CPU0_SB_DQ<4>
  VSS47  = GND
  DQ5_B  = M_E_CPU0_SB_DQ<5>
  VSS48  = GND
  DQ8_B  = M_E_CPU0_SB_DQ<8>
  VSS49  = GND
  DQ9_B  = M_E_CPU0_SB_DQ<9>
  VSS50  = GND
  DQS1_B_T  = M_E_CPU0_SB_DQS_DP<1>
  DQS1_B_C  = M_E_CPU0_SB_DQS_DN<1>
  VSS51  = GND
  DQ12_B  = M_E_CPU0_SB_DQ<12>
  VSS52  = GND
  DQ13_B  = M_E_CPU0_SB_DQ<13>
  VSS53  = GND
  DQ16_B  = M_E_CPU0_SB_DQ<16>
  VSS54  = GND
  DQ17_B  = M_E_CPU0_SB_DQ<17>
  VSS55  = GND
  DQS2_B_T  = M_E_CPU0_SB_DQS_DP<2>
  DQS2_B_C  = M_E_CPU0_SB_DQS_DN<2>
  VSS56  = GND
  DQ20_B  = M_E_CPU0_SB_DQ<20>
  VSS57  = GND
  DQ21_B  = M_E_CPU0_SB_DQ<21>
  VSS58  = GND
  DQ24_B  = M_E_CPU0_SB_DQ<24>
  VSS59  = GND
  DQ25_B  = M_E_CPU0_SB_DQ<25>
  VSS60  = GND
  DQS3_B_T  = M_E_CPU0_SB_DQS_DP<3>
  DQS3_B_C  = M_E_CPU0_SB_DQS_DN<3>
  VSS61  = GND
  DQ28_B  = M_E_CPU0_SB_DQ<28>
  VSS62  = GND
  DQ29_B  = M_E_CPU0_SB_DQ<29>
  VSS63  = GND
  RFU1  = TP_CHE_CPU0_DIMM2_FRU_1
  VIN_BULK1  = P12V_S3_AUX_CPU0_NVDIMM
  VIN_BULK2  = P12V_S3_AUX_CPU0_NVDIMM
  \pwr_good||fail_n\  = PWRGD_CHE_CPU0_DIMM2
  HSA  = PD_CHE_CPU0_DIMM2_SAA
  RFU2  = TP_CHE_CPU0_DIMM2_FRU_2
  RFU3  = TP_CHE_CPU0_DIMM2_FRU_3
  VSS64  = GND
  DQ2_A  = M_E_CPU0_SA_DQ<2>
  VSS65  = GND
  DQ3_A  = M_E_CPU0_SA_DQ<3>
  VSS66  = GND
  \dqs5_a_c||tdqs5_a_c||dqs5_a_t||tdqs5_a_t\  = M_E_CPU0_SA_DQS_DN<5>
  \dqs5_a_t||tdqs5_a_t\  = M_E_CPU0_SA_DQS_DP<5>
  VSS67  = GND
  DQ6_A  = M_E_CPU0_SA_DQ<6>
  VSS68  = GND
  DQ7_A  = M_E_CPU0_SA_DQ<7>
  VSS69  = GND
  DQ10_A  = M_E_CPU0_SA_DQ<10>
  VSS70  = GND
  DQ11_A  = M_E_CPU0_SA_DQ<11>
  VSS71  = GND
  \dqs6_a_c||tdqs6_a_c||dqs6_a_t||tdqs6_a_t\  = M_E_CPU0_SA_DQS_DN<6>
  \dqs6_a_t||tdqs6_a_t\  = M_E_CPU0_SA_DQS_DP<6>
  VSS72  = GND
  DQ14_A  = M_E_CPU0_SA_DQ<14>
  VSS73  = GND
  DQ15_A  = M_E_CPU0_SA_DQ<15>
  VSS74  = GND
  DQ18_A  = M_E_CPU0_SA_DQ<18>
  VSS75  = GND
  DQ19_A  = M_E_CPU0_SA_DQ<19>
  VSS76  = GND
  \dqs7_a_c||tdqs7_a_c\  = M_E_CPU0_SA_DQS_DN<7>
  \dqs7_a_t||tdqs7_a_t\  = M_E_CPU0_SA_DQS_DP<7>
  VSS77  = GND
  DQ22_A  = M_E_CPU0_SA_DQ<22>
  VSS78  = GND
  DQ23_A  = M_E_CPU0_SA_DQ<23>
  VSS79  = GND
  DQ26_A  = M_E_CPU0_SA_DQ<26>
  VSS80  = GND
  DQ27_A  = M_E_CPU0_SA_DQ<27>
  VSS81  = GND
  \dqs8_a_c||tdqs8_a_c\  = M_E_CPU0_SA_DQS_DN<8>
  \dqs8_a_t||tdqs8_a_t\  = M_E_CPU0_SA_DQS_DP<8>
  VSS82  = GND
  DQ30_A  = M_E_CPU0_SA_DQ<30>
  VSS83  = GND
  DQ31_A  = M_E_CPU0_SA_DQ<31>
  VSS84  = GND
  CB2_A  = M_E_CPU0_SA_CB<2>
  VSS85  = GND
  CB3_A  = M_E_CPU0_SA_CB<3>
  VSS86  = GND
  \dqs9_a_c||tdqs9_a_c\  = M_E_CPU0_SA_DQS_DN<9>
  \dqs9_a_t||tdqs9_a_t\  = M_E_CPU0_SA_DQS_DP<9>
  VSS87  = GND
  CB6_A  = M_E_CPU0_SA_CB<6>
  VSS88  = GND
  CB7_A  = M_E_CPU0_SA_CB<7>
  VSS89  = GND
  RESET_N  = RST_M_EF_CPU0_FPGA_N
  VSS90  = GND
  CS1_A_N  = M_E_CPU0_SA_CS_N<3>
  VSS91  = GND
  CA1_A  = M_E_CPU0_SA_CA<1>
  VSS92  = GND
  CA3_A  = M_E_CPU0_SA_CA<3>
  VSS93  = GND
  CA5_A  = M_E_CPU0_SA_CA<5>
  VSS94  = GND
  CK_T  = M_E_CPU0_CLK_DP<1>
  CK_C  = M_E_CPU0_CLK_DN<1>
  VSS95  = GND
  RFU4  = TP_CHE_CPU0_DIMM2_FRU_4
  CA1_B  = M_E_CPU0_SB_CA<1>
  VSS96  = GND
  CA3_B  = M_E_CPU0_SB_CA<3>
  VSS97  = GND
  CA5_B  = M_E_CPU0_SB_CA<5>
  VSS98  = GND
  PAR_B  = M_E_CPU0_SB_PAR
  VSS99  = GND
  CS1_B_N  = M_E_CPU0_SB_CS_N<3>
  VSS100  = GND
  RFU5  = TP_CHE_CPU0_DIMM2_FRU_5
  RFU6  = TP_CHE_CPU0_DIMM2_FRU_6
  VSS101  = GND
  CB6_B  = M_E_CPU0_SB_CB<6>
  VSS102  = GND
  CB7_B  = M_E_CPU0_SB_CB<7>
  VSS103  = GND
  DQS4_B_C  = M_E_CPU0_SB_DQS_DN<4>
  DQS4_B_T  = M_E_CPU0_SB_DQS_DP<4>
  VSS104  = GND
  CB2_B  = M_E_CPU0_SB_CB<2>
  VSS105  = GND
  CB3_B  = M_E_CPU0_SB_CB<3>
  VSS106  = GND
  DQ2_B  = M_E_CPU0_SB_DQ<2>
  VSS107  = GND
  DQ3_B  = M_E_CPU0_SB_DQ<3>
  VSS108  = GND
  \dqs5_b_c||tdqs5_b_c\  = M_E_CPU0_SB_DQS_DN<5>
  \dqs5_b_t||tdqs5_b_t\  = M_E_CPU0_SB_DQS_DP<5>
  VSS109  = GND
  DQ6_B  = M_E_CPU0_SB_DQ<6>
  VSS110  = GND
  DQ7_B  = M_E_CPU0_SB_DQ<7>
  VSS111  = GND
  DQ10_B  = M_E_CPU0_SB_DQ<10>
  VSS112  = GND
  DQ11_B  = M_E_CPU0_SB_DQ<11>
  VSS113  = GND
  \dqs6_b_c||tdqs6_b_c\  = M_E_CPU0_SB_DQS_DN<6>
  \dqs6_b_t||tdqs6_b_t\  = M_E_CPU0_SB_DQS_DP<6>
  VSS114  = GND
  DQ14_B  = M_E_CPU0_SB_DQ<14>
  VSS115  = GND
  DQ15_B  = M_E_CPU0_SB_DQ<15>
  VSS116  = GND
  DQ18_B  = M_E_CPU0_SB_DQ<18>
  VSS117  = GND
  DQ19_B  = M_E_CPU0_SB_DQ<19>
  VSS118  = GND
  \dqs7_b_c||tdqs7_b_c\  = M_E_CPU0_SB_DQS_DN<7>
  \dqs7_b_t||tdqs7_b_t\  = M_E_CPU0_SB_DQS_DP<7>
  VSS119  = GND
  DQ22_B  = M_E_CPU0_SB_DQ<22>
  VSS120  = GND
  DQ23_B  = M_E_CPU0_SB_DQ<23>
  VSS121  = GND
  DQ26_B  = M_E_CPU0_SB_DQ<26>
  VSS122  = GND
  DQ27_B  = M_E_CPU0_SB_DQ<27>
  VSS123  = GND
  \dqs8_b_c||tdqs8_b_c\  = M_E_CPU0_SB_DQS_DN<8>
  \dqs8_b_t||tdqs8_b_t\  = M_E_CPU0_SB_DQS_DP<8>
  VSS124  = GND
  DQ30_B  = M_E_CPU0_SB_DQ<30>
  VSS125  = GND
  DQ31_B  = M_E_CPU0_SB_DQ<31>
  VSS126  = GND
  G1  = GND
  G2  = GND
  G3  = GND

(kicad_pcb
	(version 20260206)
	(generator "pcbnew")
	(generator_version "10.0")
	(general
		(thickness 1.6)
		(legacy_teardrops no)
	)
	(paper "A4")
	(title_block
		(title "03242023_DA0F0TMBIJ0_F0T_Motherboard_J_brd_V01_OCP.brd")
		(comment 1 "Grand Teton / footprint 1607 of 6105 (J10), pads 275-291 of 291")
	)
	(layers
		(0 "F.Cu" signal "TOP")
		(4 "In1.Cu" signal "GND")
		(6 "In2.Cu" signal "IN1")
		(8 "In3.Cu" signal "GND1")
		(10 "In4.Cu" signal "IN2")
		(12 "In5.Cu" signal "GND2")
		(14 "In6.Cu" signal "IN3")
		(16 "In7.Cu" signal "GND3")
		(18 "In8.Cu" signal "VCC")
		(20 "In9.Cu" signal "VCC1")
		(22 "In10.Cu" signal "GND4")
		(24 "In11.Cu" signal "IN4")
		(26 "In12.Cu" signal "GND5")
		(28 "In13.Cu" signal "IN5")
		(30 "In14.Cu" signal "GND6")
		(32 "In15.Cu" signal "IN6")
		(34 "In16.Cu" signal "GND7")
		(2 "B.Cu" signal "BOTTOM")
		(9 "F.Adhes" user "F.Adhesive")
		(11 "B.Adhes" user "B.Adhesive")
		(13 "F.Paste" user "Package Geometry/Pastemask Top")
		(15 "B.Paste" user "Package Geometry/Pastemask Bottom")
		(5 "F.SilkS" user "Ref Des/Silkscreen Top")
		(7 "B.SilkS" user "Ref Des/Silkscreen Bottom")
		(1 "F.Mask" user "Board Geometry/Soldermask Top")
		(3 "B.Mask" user "Board Geometry/Soldermask Bottom")
		(17 "Dwgs.User" user "User.Drawings")
		(19 "Cmts.User" user "User.Comments")
		(21 "Eco1.User" user "User.Eco1")
		(23 "Eco2.User" user "User.Eco2")
		(25 "Edge.Cuts" user "Board Geometry/Outline")
		(27 "Margin" user)
		(31 "F.CrtYd" user "Package Geometry/Place Bound Top")
		(29 "B.CrtYd" user "Package Geometry/Place Bound Bottom")
		(35 "F.Fab" user "Ref Des/Assembly Top")
		(33 "B.Fab" user "Ref Des/Assembly Bottom")
	)
	(footprint ""
		(layer "F.Cu")
		(at 408.803348 -258.091686)
		(property "Reference" "J10"
			(at -3.683 -81.702148 0)
			(unlocked yes)
			(layer "F.SilkS")
			(effects
				(font
					(size 0.7874 0.5842)
					(thickness 0.1524)
				)
				(justify left)
			)
		)
		(property "Value" ""
			(at 0 0 0)
			(layer "F.Fab")
			(effects
				(font
					(size 1.27 1.27)
				)
			)
		)
		(duplicate_pad_numbers_are_jumpers no)
		(pad "275" smd rect
			(at 2.050034 52.274978 270)
			(size 0.519938 1.4986)
			(layers "F.Cu" "F.Mask" "F.Paste")
			(net "GND")
		)
		(pad "276" smd rect
			(at 2.050034 53.125116 270)
			(size 0.519938 1.4986)
			(layers "F.Cu" "F.Mask" "F.Paste")
			(net "M_E_CPU0_SB_DQ<23>")
		)
		(pad "277" smd rect
			(at 2.050034 53.975 270)
			(size 0.519938 1.4986)
			(layers "F.Cu" "F.Mask" "F.Paste")
			(net "GND")
		)
		(pad "278" smd rect
			(at 2.050034 54.824884 270)
			(size 0.519938 1.4986)
			(layers "F.Cu" "F.Mask" "F.Paste")
			(net "M_E_CPU0_SB_DQ<26>")
		)
		(pad "279" smd rect
			(at 2.050034 55.675022 270)
			(size 0.519938 1.4986)
			(layers "F.Cu" "F.Mask" "F.Paste")
			(net "GND")
		)
		(pad "280" smd rect
			(at 2.050034 56.524906 270)
			(size 0.519938 1.4986)
			(layers "F.Cu" "F.Mask" "F.Paste")
			(net "M_E_CPU0_SB_DQ<27>")
		)
		(pad "281" smd rect
			(at 2.050034 57.375044 270)
			(size 0.519938 1.4986)
			(layers "F.Cu" "F.Mask" "F.Paste")
			(net "GND")
		)
		(pad "282" smd rect
			(at 2.050034 58.224928 270)
			(size 0.519938 1.4986)
			(layers "F.Cu" "F.Mask" "F.Paste")
			(net "M_E_CPU0_SB_DQS_DN<8>")
		)
		(pad "283" smd rect
			(at 2.050034 59.075066 270)
			(size 0.519938 1.4986)
			(layers "F.Cu" "F.Mask" "F.Paste")
			(net "M_E_CPU0_SB_DQS_DP<8>")
		)
		(pad "284" smd rect
			(at 2.050034 59.92495 270)
			(size 0.519938 1.4986)
			(layers "F.Cu" "F.Mask" "F.Paste")
			(net "GND")
		)
		(pad "285" smd rect
			(at 2.050034 60.775088 270)
			(size 0.519938 1.4986)
			(layers "F.Cu" "F.Mask" "F.Paste")
			(net "M_E_CPU0_SB_DQ<30>")
		)
		(pad "286" smd rect
			(at 2.050034 61.624972 270)
			(size 0.519938 1.4986)
			(layers "F.Cu" "F.Mask" "F.Paste")
			(net "GND")
		)
		(pad "287" smd rect
			(at 2.050034 62.47511 270)
			(size 0.519938 1.4986)
			(layers "F.Cu" "F.Mask" "F.Paste")
			(net "M_E_CPU0_SB_DQ<31>")
		)
		(pad "288" smd rect
			(at 2.050034 63.324994 270)
			(size 0.519938 1.4986)
			(layers "F.Cu" "F.Mask" "F.Paste")
			(net "GND")
		)
		(pad "G1" thru_hole oval
			(at 0 -68.97497)
			(size 2.8194 1.5748)
			(drill oval 2.4384 1.1938)
			(layers "*.Cu" "*.Mask")
			(remove_unused_layers no)
			(net "GND")
			(clearance 0.127)
			(thermal_gap 0.127)
		)
		(pad "G2" thru_hole oval
			(at 0 3.875024)
			(size 2.8194 1.5748)
			(drill oval 2.4384 1.1938)
			(layers "*.Cu" "*.Mask")
			(remove_unused_layers no)
			(net "GND")
			(clearance 0.127)
			(thermal_gap 0.127)
		)
		(pad "G3" thru_hole oval
			(at 0 68.97497)
			(size 2.8194 1.5748)
			(drill oval 2.4384 1.1938)
			(layers "*.Cu" "*.Mask")
			(remove_unused_layers no)
			(net "GND")
			(clearance 0.127)
			(thermal_gap 0.127)
		)
	)
)
